Created on Valor NPI 9.6 Update 2 - Netlist Compare Summary.
DATE :  10 Feb 2017
TIME :  17:40:41


     MISMATCH SUMMARY REPORT
     -----------------------

Job  : 15126-1b                Job  : 15126-1b
Step : db                      Step : db
Type : CAD                     Type : CURCAD

-----------------------------------------------

 Mismatch Type: shorted

   GND                   -   NET00052            
   VSENSE_PVDDQ_GHJ_N    -    "                  
   VSENSE_PVDDQ_ABC_N    -    "                  
   VSENSE_PVDDQ_KLM_N    -    "                  
   VSENSE_PVDDQ_DEF_N    -    "                  
   PVDDQ_ABC             -   NET00061            
   VSENSE_PVDDQ_ABC_P    -    "                  
   VSENSE_PVDDQ_GHJ_P    -   NET00072            
   PVDDQ_GHJ             -    "                  
   PVTT_GHJ              -   NET00078            
   VR_PVTT_GHJ_SNS       -    "                  
   PVTT_ABC              -   NET00079            
   VR_PVTT_ABC_SNS       -    "                  
   VSENSE_PVCCIO_CPU0_SKT_VSEN  -   NET02581            
   VSENSE_PVCCIO_CPU0_AVSP  -    "                  
   VSENSE_PVCCIO_CPU0_SKT_VRTN  -   NET02582            
   VSENSE_PVCCIO_CPU0_AVSN  -    "                  
   VSENSE_PVCCIO_CPU1_SKT_VSEN  -   NET03027            
   VSENSE_PVCCIO_CPU1_AVSP  -    "                  
   VSENSE_PVCCIO_CPU1_AVSN  -   NET03042            
   VSENSE_PVCCIO_CPU1_SKT_VRTN  -    "                  
   PVDDQ_DEF             -   NET03879            
   VSENSE_PVDDQ_DEF_P    -    "                  
   PVDDQ_KLM             -   NET03880            
   VSENSE_PVDDQ_KLM_P    -    "                  
   PVTT_KLM              -   NET05982            
   VR_PVTT_KLM_SNS       -    "                  
   PVTT_DEF              -   NET05983            
   VR_PVTT_DEF_SNS       -    "                  

 Total : 13
-----------------------------------------------

 Mismatch Type: broken

   GND                   -   NET00000            
    "                    -   NET06367            
    "                    -   NET00052            

 Total : 1
-----------------------------------------------

 Mismatch Type: missing


 Total : 0
-----------------------------------------------

 Mismatch Type: extra


 Total : 0
-----------------------------------------------
